(kicad_pcb
	(version 20260206)
	(generator "pcbnew")
	(generator_version "10.0")
	(general
		(thickness 1.6)
		(legacy_teardrops no)
	)
	(paper "A4")
	(title_block
		(title "03242023_DA0F0TMBIJ0_F0T_Motherboard_J_brd_V01_OCP.brd")
		(comment 1 "Grand Teton / footprints 1100-1107 of 6105")
	)
	(layers
		(0 "F.Cu" signal "TOP")
		(4 "In1.Cu" signal "GND")
		(6 "In2.Cu" signal "IN1")
		(8 "In3.Cu" signal "GND1")
		(10 "In4.Cu" signal "IN2")
		(12 "In5.Cu" signal "GND2")
		(14 "In6.Cu" signal "IN3")
		(16 "In7.Cu" signal "GND3")
		(18 "In8.Cu" signal "VCC")
		(20 "In9.Cu" signal "VCC1")
		(22 "In10.Cu" signal "GND4")
		(24 "In11.Cu" signal "IN4")
		(26 "In12.Cu" signal "GND5")
		(28 "In13.Cu" signal "IN5")
		(30 "In14.Cu" signal "GND6")
		(32 "In15.Cu" signal "IN6")
		(34 "In16.Cu" signal "GND7")
		(2 "B.Cu" signal "BOTTOM")
		(9 "F.Adhes" user "F.Adhesive")
		(11 "B.Adhes" user "B.Adhesive")
		(13 "F.Paste" user "Package Geometry/Pastemask Top")
		(15 "B.Paste" user "Package Geometry/Pastemask Bottom")
		(5 "F.SilkS" user "Ref Des/Silkscreen Top")
		(7 "B.SilkS" user "Ref Des/Silkscreen Bottom")
		(1 "F.Mask" user "Board Geometry/Soldermask Top")
		(3 "B.Mask" user "Board Geometry/Soldermask Bottom")
		(17 "Dwgs.User" user "User.Drawings")
		(19 "Cmts.User" user "User.Comments")
		(21 "Eco1.User" user "User.Eco1")
		(23 "Eco2.User" user "User.Eco2")
		(25 "Edge.Cuts" user "Board Geometry/Outline")
		(27 "Margin" user)
		(31 "F.CrtYd" user "Package Geometry/Place Bound Top")
		(29 "B.CrtYd" user "Package Geometry/Place Bound Bottom")
		(35 "F.Fab" user "Ref Des/Assembly Top")
		(33 "B.Fab" user "Ref Des/Assembly Bottom")
	)
	(footprint ""
		(layer "F.Cu")
		(at 403.946106 -65.085976 180)
		(property "Reference" "R767"
			(at 0 0 180)
			(layer "F.SilkS")
			(hide yes)
			(effects
				(font
					(size 1.27 1.27)
				)
			)
		)
		(property "Value" ""
			(at 0 0 180)
			(layer "F.Fab")
			(effects
				(font
					(size 1.27 1.27)
				)
			)
		)
		(duplicate_pad_numbers_are_jumpers no)
		(fp_line
			(start 0.7874 0.4064)
			(end -0.7874 0.4064)
			(stroke
				(width 0.1524)
				(type default)
			)
			(layer "F.SilkS")
		)
		(fp_line
			(start 0.7874 -0.4064)
			(end 0.7874 0.4064)
			(stroke
				(width 0.1524)
				(type default)
			)
			(layer "F.SilkS")
		)
		(fp_line
			(start -0.7874 0.4064)
			(end -0.7874 -0.4064)
			(stroke
				(width 0.1524)
				(type default)
			)
			(layer "F.SilkS")
		)
		(fp_line
			(start -0.7874 -0.4064)
			(end 0.7874 -0.4064)
			(stroke
				(width 0.1524)
				(type default)
			)
			(layer "F.SilkS")
		)
		(fp_line
			(start 0.67945 0.3048)
			(end 0.120396 0.3048)
			(stroke
				(width 0.1)
				(type default)
			)
			(layer "F.Fab")
		)
		(fp_line
			(start 0.67945 -0.3048)
			(end 0.67945 0.3048)
			(stroke
				(width 0.1)
				(type default)
			)
			(layer "F.Fab")
		)
		(fp_line
			(start 0.12065 -0.2794)
			(end 0.12065 -0.3048)
			(stroke
				(width 0.1)
				(type default)
			)
			(layer "F.Fab")
		)
		(fp_line
			(start 0.12065 -0.3048)
			(end 0.67945 -0.3048)
			(stroke
				(width 0.1)
				(type default)
			)
			(layer "F.Fab")
		)
		(fp_line
			(start 0.120396 0.3048)
			(end 0.120396 0.2794)
			(stroke
				(width 0.1)
				(type default)
			)
			(layer "F.Fab")
		)
		(fp_line
			(start 0.120396 0.2794)
			(end -0.12065 0.2794)
			(stroke
				(width 0.1)
				(type default)
			)
			(layer "F.Fab")
		)
		(fp_line
			(start -0.12065 0.3048)
			(end -0.67945 0.3048)
			(stroke
				(width 0.1)
				(type default)
			)
			(layer "F.Fab")
		)
		(fp_line
			(start -0.12065 0.2794)
			(end -0.12065 0.3048)
			(stroke
				(width 0.1)
				(type default)
			)
			(layer "F.Fab")
		)
		(fp_line
			(start -0.12065 -0.2794)
			(end 0.12065 -0.2794)
			(stroke
				(width 0.1)
				(type default)
			)
			(layer "F.Fab")
		)
		(fp_line
			(start -0.12065 -0.305054)
			(end -0.12065 -0.2794)
			(stroke
				(width 0.1)
				(type default)
			)
			(layer "F.Fab")
		)
		(fp_line
			(start -0.67945 0.3048)
			(end -0.67945 -0.305054)
			(stroke
				(width 0.1)
				(type default)
			)
			(layer "F.Fab")
		)
		(fp_line
			(start -0.67945 -0.305054)
			(end -0.12065 -0.305054)
			(stroke
				(width 0.1)
				(type default)
			)
			(layer "F.Fab")
		)
		(pad "1" smd circle
			(at -0.40005 0 180)
			(size 0 0)
			(layers "F.Cu" "F.Mask" "F.Paste")
			(net "P3V3_AUX")
		)
		(pad "2" smd circle
			(at 0.40005 0 180)
			(size 0 0)
			(layers "F.Cu" "F.Mask" "F.Paste")
			(net "JTAG_RST_DBP_RST_CO_N")
		)
	)
	(footprint ""
		(layer "F.Cu")
		(at 96.797876 -79.078836)
		(property "Reference" "D95"
			(at -48.49241 38.649402 90)
			(unlocked yes)
			(layer "F.SilkS")
			(effects
				(font
					(size 0.635 0.4064)
					(thickness 0.1524)
				)
				(justify left)
			)
		)
		(property "Value" ""
			(at 0 0 0)
			(layer "F.Fab")
			(effects
				(font
					(size 1.27 1.27)
				)
			)
		)
		(duplicate_pad_numbers_are_jumpers no)
		(fp_line
			(start -0.90678 0.4826)
			(end -0.90678 -0.4699)
			(stroke
				(width 0.1524)
				(type default)
			)
			(layer "F.SilkS")
		)
		(fp_line
			(start -0.89408 -0.4826)
			(end 0.90678 -0.4826)
			(stroke
				(width 0.1524)
				(type default)
			)
			(layer "F.SilkS")
		)
		(fp_line
			(start -0.79248 -0.4826)
			(end 1.03378 -0.4826)
			(stroke
				(width 0.1524)
				(type default)
			)
			(layer "F.SilkS")
		)
		(fp_line
			(start -0.64008 -0.4826)
			(end 1.16078 -0.4826)
			(stroke
				(width 0.1524)
				(type default)
			)
			(layer "F.SilkS")
		)
		(fp_line
			(start 0.90678 -0.4826)
			(end 0.90678 0.4826)
			(stroke
				(width 0.1524)
				(type default)
			)
			(layer "F.SilkS")
		)
		(fp_line
			(start 0.90678 0.4826)
			(end -0.90678 0.4826)
			(stroke
				(width 0.1524)
				(type default)
			)
			(layer "F.SilkS")
		)
		(fp_line
			(start 1.03378 -0.4826)
			(end 1.03378 0.4826)
			(stroke
				(width 0.1524)
				(type default)
			)
			(layer "F.SilkS")
		)
		(fp_line
			(start 1.03378 0.4826)
			(end -0.79248 0.4826)
			(stroke
				(width 0.1524)
				(type default)
			)
			(layer "F.SilkS")
		)
		(fp_line
			(start 1.16078 -0.4826)
			(end 1.16078 0.4826)
			(stroke
				(width 0.1524)
				(type default)
			)
			(layer "F.SilkS")
		)
		(fp_line
			(start 1.16078 0.4826)
			(end -0.64008 0.4826)
			(stroke
				(width 0.1524)
				(type default)
			)
			(layer "F.SilkS")
		)
		(fp_line
			(start -0.499872 -0.249936)
			(end 0.499872 -0.249936)
			(stroke
				(width 0.1)
				(type default)
			)
			(layer "F.Fab")
		)
		(fp_line
			(start -0.499872 0.249936)
			(end -0.499872 -0.249936)
			(stroke
				(width 0.1)
				(type default)
			)
			(layer "F.Fab")
		)
		(fp_line
			(start 0.499872 -0.249936)
			(end 0.499872 0.249936)
			(stroke
				(width 0.1)
				(type default)
			)
			(layer "F.Fab")
		)
		(fp_line
			(start 0.499872 0.249936)
			(end -0.499872 0.249936)
			(stroke
				(width 0.1)
				(type default)
			)
			(layer "F.Fab")
		)
		(pad "A" smd rect
			(at -0.47498 0)
			(size 0.6096 0.7112)
			(layers "F.Cu" "F.Mask" "F.Paste")
			(net "LED_FM_PCH_SLP_S3_N")
		)
		(pad "C" smd rect
			(at 0.47498 0)
			(size 0.6096 0.7112)
			(layers "F.Cu" "F.Mask" "F.Paste")
			(net "LED_FM_PCH_SLP_S3_N_D")
		)
	)
	(footprint ""
		(layer "F.Cu")
		(at 356.28072 -406.850088 90)
		(property "Reference" "R4547"
			(at 0 0 90)
			(layer "F.SilkS")
			(hide yes)
			(effects
				(font
					(size 1.27 1.27)
				)
			)
		)
		(property "Value" ""
			(at 0 0 90)
			(layer "F.Fab")
			(effects
				(font
					(size 1.27 1.27)
				)
			)
		)
		(duplicate_pad_numbers_are_jumpers no)
		(fp_line
			(start 0.7874 -0.4064)
			(end 0.7874 0.4064)
			(stroke
				(width 0.1524)
				(type default)
			)
			(layer "F.SilkS")
		)
		(fp_line
			(start -0.7874 -0.4064)
			(end 0.7874 -0.4064)
			(stroke
				(width 0.1524)
				(type default)
			)
			(layer "F.SilkS")
		)
		(fp_line
			(start 0.7874 0.4064)
			(end -0.7874 0.4064)
			(stroke
				(width 0.1524)
				(type default)
			)
			(layer "F.SilkS")
		)
		(fp_line
			(start -0.7874 0.4064)
			(end -0.7874 -0.4064)
			(stroke
				(width 0.1524)
				(type default)
			)
			(layer "F.SilkS")
		)
		(fp_line
			(start -0.12065 -0.305054)
			(end -0.12065 -0.2794)
			(stroke
				(width 0.1)
				(type default)
			)
			(layer "F.Fab")
		)
		(fp_line
			(start -0.67945 -0.305054)
			(end -0.12065 -0.305054)
			(stroke
				(width 0.1)
				(type default)
			)
			(layer "F.Fab")
		)
		(fp_line
			(start 0.67945 -0.3048)
			(end 0.67945 0.3048)
			(stroke
				(width 0.1)
				(type default)
			)
			(layer "F.Fab")
		)
		(fp_line
			(start 0.12065 -0.3048)
			(end 0.67945 -0.3048)
			(stroke
				(width 0.1)
				(type default)
			)
			(layer "F.Fab")
		)
		(fp_line
			(start 0.12065 -0.2794)
			(end 0.12065 -0.3048)
			(stroke
				(width 0.1)
				(type default)
			)
			(layer "F.Fab")
		)
		(fp_line
			(start -0.12065 -0.2794)
			(end 0.12065 -0.2794)
			(stroke
				(width 0.1)
				(type default)
			)
			(layer "F.Fab")
		)
		(fp_line
			(start 0.120396 0.2794)
			(end -0.12065 0.2794)
			(stroke
				(width 0.1)
				(type default)
			)
			(layer "F.Fab")
		)
		(fp_line
			(start -0.12065 0.2794)
			(end -0.12065 0.3048)
			(stroke
				(width 0.1)
				(type default)
			)
			(layer "F.Fab")
		)
		(fp_line
			(start 0.67945 0.3048)
			(end 0.120396 0.3048)
			(stroke
				(width 0.1)
				(type default)
			)
			(layer "F.Fab")
		)
		(fp_line
			(start 0.120396 0.3048)
			(end 0.120396 0.2794)
			(stroke
				(width 0.1)
				(type default)
			)
			(layer "F.Fab")
		)
		(fp_line
			(start -0.12065 0.3048)
			(end -0.67945 0.3048)
			(stroke
				(width 0.1)
				(type default)
			)
			(layer "F.Fab")
		)
		(fp_line
			(start -0.67945 0.3048)
			(end -0.67945 -0.305054)
			(stroke
				(width 0.1)
				(type default)
			)
			(layer "F.Fab")
		)
		(pad "1" smd circle
			(at -0.40005 0 90)
			(size 0 0)
			(layers "F.Cu" "F.Mask" "F.Paste")
			(net "P3V3_AUX")
		)
		(pad "2" smd circle
			(at 0.40005 0 90)
			(size 0 0)
			(layers "F.Cu" "F.Mask" "F.Paste")
			(net "SWB_HSC_EN")
		)
	)
	(footprint ""
		(layer "F.Cu")
		(at 125.453394 -408.517344 -90)
		(property "Reference" "C1519"
			(at 0 0 270)
			(layer "F.SilkS")
			(hide yes)
			(effects
				(font
					(size 1.27 1.27)
				)
			)
		)
		(property "Value" ""
			(at 0 0 270)
			(layer "F.Fab")
			(effects
				(font
					(size 1.27 1.27)
				)
			)
		)
		(duplicate_pad_numbers_are_jumpers no)
		(fp_line
			(start -0.299974 0.150114)
			(end -0.299974 -0.150114)
			(stroke
				(width 0.1)
				(type default)
			)
			(layer "F.Fab")
		)
		(fp_line
			(start 0.299974 0.150114)
			(end -0.299974 0.150114)
			(stroke
				(width 0.1)
				(type default)
			)
			(layer "F.Fab")
		)
		(fp_line
			(start -0.299974 -0.150114)
			(end 0.299974 -0.150114)
			(stroke
				(width 0.1)
				(type default)
			)
			(layer "F.Fab")
		)
		(fp_line
			(start 0.299974 -0.150114)
			(end 0.299974 0.150114)
			(stroke
				(width 0.1)
				(type default)
			)
			(layer "F.Fab")
		)
		(pad "1" smd rect
			(at -0.2667 0 270)
			(size 0.3048 0.381)
			(layers "F.Cu" "F.Mask" "F.Paste")
			(net "P5E_CPU1_PE3_TX_C_DP<14>")
		)
		(pad "2" smd rect
			(at 0.2667 0 270)
			(size 0.3048 0.381)
			(layers "F.Cu" "F.Mask" "F.Paste")
			(net "P5E_CPU1_PE3_TX_DP<14>")
		)
	)
	(footprint ""
		(layer "F.Cu")
		(at 430.277016 -101.97719 180)
		(property "Reference" "R3783"
			(at 0 0 180)
			(layer "F.SilkS")
			(hide yes)
			(effects
				(font
					(size 1.27 1.27)
				)
			)
		)
		(property "Value" ""
			(at 0 0 180)
			(layer "F.Fab")
			(effects
				(font
					(size 1.27 1.27)
				)
			)
		)
		(duplicate_pad_numbers_are_jumpers no)
		(fp_line
			(start 0.7874 0.4064)
			(end -0.7874 0.4064)
			(stroke
				(width 0.1524)
				(type default)
			)
			(layer "F.SilkS")
		)
		(fp_line
			(start 0.7874 -0.4064)
			(end 0.7874 0.4064)
			(stroke
				(width 0.1524)
				(type default)
			)
			(layer "F.SilkS")
		)
		(fp_line
			(start -0.7874 0.4064)
			(end -0.7874 -0.4064)
			(stroke
				(width 0.1524)
				(type default)
			)
			(layer "F.SilkS")
		)
		(fp_line
			(start -0.7874 -0.4064)
			(end 0.7874 -0.4064)
			(stroke
				(width 0.1524)
				(type default)
			)
			(layer "F.SilkS")
		)
		(fp_line
			(start 0.67945 0.3048)
			(end 0.120396 0.3048)
			(stroke
				(width 0.1)
				(type default)
			)
			(layer "F.Fab")
		)
		(fp_line
			(start 0.67945 -0.3048)
			(end 0.67945 0.3048)
			(stroke
				(width 0.1)
				(type default)
			)
			(layer "F.Fab")
		)
		(fp_line
			(start 0.12065 -0.2794)
			(end 0.12065 -0.3048)
			(stroke
				(width 0.1)
				(type default)
			)
			(layer "F.Fab")
		)
		(fp_line
			(start 0.12065 -0.3048)
			(end 0.67945 -0.3048)
			(stroke
				(width 0.1)
				(type default)
			)
			(layer "F.Fab")
		)
		(fp_line
			(start 0.120396 0.3048)
			(end 0.120396 0.2794)
			(stroke
				(width 0.1)
				(type default)
			)
			(layer "F.Fab")
		)
		(fp_line
			(start 0.120396 0.2794)
			(end -0.12065 0.2794)
			(stroke
				(width 0.1)
				(type default)
			)
			(layer "F.Fab")
		)
		(fp_line
			(start -0.12065 0.3048)
			(end -0.67945 0.3048)
			(stroke
				(width 0.1)
				(type default)
			)
			(layer "F.Fab")
		)
		(fp_line
			(start -0.12065 0.2794)
			(end -0.12065 0.3048)
			(stroke
				(width 0.1)
				(type default)
			)
			(layer "F.Fab")
		)
		(fp_line
			(start -0.12065 -0.2794)
			(end 0.12065 -0.2794)
			(stroke
				(width 0.1)
				(type default)
			)
			(layer "F.Fab")
		)
		(fp_line
			(start -0.12065 -0.305054)
			(end -0.12065 -0.2794)
			(stroke
				(width 0.1)
				(type default)
			)
			(layer "F.Fab")
		)
		(fp_line
			(start -0.67945 0.3048)
			(end -0.67945 -0.305054)
			(stroke
				(width 0.1)
				(type default)
			)
			(layer "F.Fab")
		)
		(fp_line
			(start -0.67945 -0.305054)
			(end -0.12065 -0.305054)
			(stroke
				(width 0.1)
				(type default)
			)
			(layer "F.Fab")
		)
		(pad "1" smd circle
			(at -0.40005 0 180)
			(size 0 0)
			(layers "F.Cu" "F.Mask" "F.Paste")
			(net "P3V3_AUX")
		)
		(pad "2" smd circle
			(at 0.40005 0 180)
			(size 0 0)
			(layers "F.Cu" "F.Mask" "F.Paste")
			(net "OCP_V3_1_P3V3_PWRGD")
		)
	)
	(footprint ""
		(layer "F.Cu")
		(at 37.860478 -16.099536 90)
		(property "Reference" "C823"
			(at 0 0 90)
			(layer "F.SilkS")
			(hide yes)
			(effects
				(font
					(size 1.27 1.27)
				)
			)
		)
		(property "Value" ""
			(at 0 0 90)
			(layer "F.Fab")
			(effects
				(font
					(size 1.27 1.27)
				)
			)
		)
		(duplicate_pad_numbers_are_jumpers no)
		(fp_line
			(start 0.299974 -0.150114)
			(end 0.299974 0.150114)
			(stroke
				(width 0.1)
				(type default)
			)
			(layer "F.Fab")
		)
		(fp_line
			(start -0.299974 -0.150114)
			(end 0.299974 -0.150114)
			(stroke
				(width 0.1)
				(type default)
			)
			(layer "F.Fab")
		)
		(fp_line
			(start 0.299974 0.150114)
			(end -0.299974 0.150114)
			(stroke
				(width 0.1)
				(type default)
			)
			(layer "F.Fab")
		)
		(fp_line
			(start -0.299974 0.150114)
			(end -0.299974 -0.150114)
			(stroke
				(width 0.1)
				(type default)
			)
			(layer "F.Fab")
		)
		(pad "1" smd rect
			(at -0.2667 0 90)
			(size 0.3048 0.381)
			(layers "F.Cu" "F.Mask" "F.Paste")
			(net "P5E_CPU1_PE1_TX_C_DP<7>")
		)
		(pad "2" smd rect
			(at 0.2667 0 90)
			(size 0.3048 0.381)
			(layers "F.Cu" "F.Mask" "F.Paste")
			(net "P5E_CPU1_PE1_TX_DP<7>")
		)
	)
	(footprint ""
		(layer "F.Cu")
		(at 388.72541 -35.731196 90)
		(property "Reference" "U52"
			(at 3.957828 -0.994918 0)
			(unlocked yes)
			(layer "F.SilkS")
			(effects
				(font
					(size 0.7874 0.5842)
					(thickness 0.1524)
				)
				(justify left)
			)
		)
		(property "Value" ""
			(at 0 0 90)
			(layer "F.Fab")
			(effects
				(font
					(size 1.27 1.27)
				)
			)
		)
		(duplicate_pad_numbers_are_jumpers no)
		(fp_line
			(start 1.759712 -1.500124)
			(end 1.759712 1.500124)
			(stroke
				(width 0.1524)
				(type default)
			)
			(layer "F.SilkS")
		)
		(fp_line
			(start -1.759712 -1.500124)
			(end 1.759712 -1.500124)
			(stroke
				(width 0.1524)
				(type default)
			)
			(layer "F.SilkS")
		)
		(fp_line
			(start 1.759712 1.500124)
			(end -1.759712 1.500124)
			(stroke
				(width 0.1524)
				(type default)
			)
			(layer "F.SilkS")
		)
		(fp_line
			(start -1.759712 1.500124)
			(end -1.759712 -1.500124)
			(stroke
				(width 0.1524)
				(type default)
			)
			(layer "F.SilkS")
		)
		(fp_line
			(start 0.700024 -1.500124)
			(end 0.700024 1.500124)
			(stroke
				(width 0.1)
				(type default)
			)
			(layer "F.Fab")
		)
		(fp_line
			(start -0.700024 -1.500124)
			(end 0.700024 -1.500124)
			(stroke
				(width 0.1)
				(type default)
			)
			(layer "F.Fab")
		)
		(fp_line
			(start 0.700024 1.500124)
			(end -0.700024 1.500124)
			(stroke
				(width 0.1)
				(type default)
			)
			(layer "F.Fab")
		)
		(fp_line
			(start -0.700024 1.500124)
			(end -0.700024 -1.500124)
			(stroke
				(width 0.1)
				(type default)
			)
			(layer "F.Fab")
		)
		(pad "1" smd rect
			(at -1.150112 -0.94996)
			(size 0.6604 0.9652)
			(layers "F.Cu" "F.Mask" "F.Paste")
			(net "GND")
		)
		(pad "2" smd rect
			(at -1.150112 0.94996)
			(size 0.6604 0.9652)
			(layers "F.Cu" "F.Mask" "F.Paste")
			(net "HP_OCP_V3_1_RST")
		)
		(pad "3" smd rect
			(at 1.150112 0)
			(size 0.6604 0.9652)
			(layers "F.Cu" "F.Mask" "F.Paste")
			(net "P3V3_OCP_SFF")
		)
	)
	(footprint ""
		(layer "F.Cu")
		(at 54.242716 -110.93069 180)
		(property "Reference" "R3715"
			(at 0 0 180)
			(layer "F.SilkS")
			(hide yes)
			(effects
				(font
					(size 1.27 1.27)
				)
			)
		)
		(property "Value" ""
			(at 0 0 180)
			(layer "F.Fab")
			(effects
				(font
					(size 1.27 1.27)
				)
			)
		)
		(duplicate_pad_numbers_are_jumpers no)
		(fp_line
			(start 0.7874 0.4064)
			(end -0.7874 0.4064)
			(stroke
				(width 0.1524)
				(type default)
			)
			(layer "F.SilkS")
		)
		(fp_line
			(start 0.7874 -0.4064)
			(end 0.7874 0.4064)
			(stroke
				(width 0.1524)
				(type default)
			)
			(layer "F.SilkS")
		)
		(fp_line
			(start -0.7874 0.4064)
			(end -0.7874 -0.4064)
			(stroke
				(width 0.1524)
				(type default)
			)
			(layer "F.SilkS")
		)
		(fp_line
			(start -0.7874 -0.4064)
			(end 0.7874 -0.4064)
			(stroke
				(width 0.1524)
				(type default)
			)
			(layer "F.SilkS")
		)
		(fp_line
			(start 0.67945 0.3048)
			(end 0.120396 0.3048)
			(stroke
				(width 0.1)
				(type default)
			)
			(layer "F.Fab")
		)
		(fp_line
			(start 0.67945 -0.3048)
			(end 0.67945 0.3048)
			(stroke
				(width 0.1)
				(type default)
			)
			(layer "F.Fab")
		)
		(fp_line
			(start 0.12065 -0.2794)
			(end 0.12065 -0.3048)
			(stroke
				(width 0.1)
				(type default)
			)
			(layer "F.Fab")
		)
		(fp_line
			(start 0.12065 -0.3048)
			(end 0.67945 -0.3048)
			(stroke
				(width 0.1)
				(type default)
			)
			(layer "F.Fab")
		)
		(fp_line
			(start 0.120396 0.3048)
			(end 0.120396 0.2794)
			(stroke
				(width 0.1)
				(type default)
			)
			(layer "F.Fab")
		)
		(fp_line
			(start 0.120396 0.2794)
			(end -0.12065 0.2794)
			(stroke
				(width 0.1)
				(type default)
			)
			(layer "F.Fab")
		)
		(fp_line
			(start -0.12065 0.3048)
			(end -0.67945 0.3048)
			(stroke
				(width 0.1)
				(type default)
			)
			(layer "F.Fab")
		)
		(fp_line
			(start -0.12065 0.2794)
			(end -0.12065 0.3048)
			(stroke
				(width 0.1)
				(type default)
			)
			(layer "F.Fab")
		)
		(fp_line
			(start -0.12065 -0.2794)
			(end 0.12065 -0.2794)
			(stroke
				(width 0.1)
				(type default)
			)
			(layer "F.Fab")
		)
		(fp_line
			(start -0.12065 -0.305054)
			(end -0.12065 -0.2794)
			(stroke
				(width 0.1)
				(type default)
			)
			(layer "F.Fab")
		)
		(fp_line
			(start -0.67945 0.3048)
			(end -0.67945 -0.305054)
			(stroke
				(width 0.1)
				(type default)
			)
			(layer "F.Fab")
		)
		(fp_line
			(start -0.67945 -0.305054)
			(end -0.12065 -0.305054)
			(stroke
				(width 0.1)
				(type default)
			)
			(layer "F.Fab")
		)
		(pad "1" smd circle
			(at -0.40005 0 180)
			(size 0 0)
			(layers "F.Cu" "F.Mask" "F.Paste")
			(net "SMB_LM75_0_3V3AUX_SCL_R")
		)
		(pad "2" smd circle
			(at 0.40005 0 180)
			(size 0 0)
			(layers "F.Cu" "F.Mask" "F.Paste")
			(net "SMB_LM75_0_3V3AUX_SCL")
		)
	)
)
